(kicad_pcb
	(version 20260206)
	(generator "pcbnew")
	(generator_version "10.0")
	(general
		(thickness 1.6)
		(legacy_teardrops no)
	)
	(paper "A4")
	(title_block
		(title "dpb — 14545-sa.0730WZS0815.brd")
		(comment 1 "Honey Badger (Wiwynn) / footprints 815-822 of 1066")
	)
	(layers
		(0 "F.Cu" signal "TOP")
		(4 "In1.Cu" signal "L2GND")
		(6 "In2.Cu" signal "L3")
		(8 "In3.Cu" signal "L4VCC")
		(10 "In4.Cu" signal "L5VCC")
		(12 "In5.Cu" signal "L6")
		(14 "In6.Cu" signal "L7GND")
		(2 "B.Cu" signal "BOTTOM")
		(9 "F.Adhes" user "F.Adhesive")
		(11 "B.Adhes" user "B.Adhesive")
		(13 "F.Paste" user "Package Geometry/Pastemask Top")
		(15 "B.Paste" user "Package Geometry/Pastemask Bottom")
		(5 "F.SilkS" user "Ref Des/Silkscreen Top")
		(7 "B.SilkS" user "Ref Des/Silkscreen Bottom")
		(1 "F.Mask" user "Board Geometry/Soldermask Top")
		(3 "B.Mask" user "Board Geometry/Soldermask Bottom")
		(17 "Dwgs.User" user "User.Drawings")
		(19 "Cmts.User" user "User.Comments")
		(21 "Eco1.User" user "User.Eco1")
		(23 "Eco2.User" user "User.Eco2")
		(25 "Edge.Cuts" user "Board Geometry/Outline")
		(27 "Margin" user)
		(31 "F.CrtYd" user "Package Geometry/Place Bound Top")
		(29 "B.CrtYd" user "Package Geometry/Place Bound Bottom")
		(35 "F.Fab" user "Ref Des/Assembly Top")
		(33 "B.Fab" user "Ref Des/Assembly Bottom")
	)
	(footprint ""
		(layer "F.Cu")
		(at 236.854746 -27.9527 180)
		(property "Reference" "PR11"
			(at 0 0 180)
			(layer "F.SilkS")
			(hide yes)
			(effects
				(font
					(size 1.27 1.27)
				)
			)
		)
		(property "Value" "73K2R2F-GP"
			(at 0.064008 -3.993896 180)
			(unlocked yes)
			(layer "F.Fab")
			(hide yes)
			(effects
				(font
					(size 1.016 1.016)
					(thickness 0.1524)
				)
			)
		)
		(property "Device Type" "R402H16"
			(at 0.064008 -5.517896 180)
			(unlocked yes)
			(layer "F.Fab")
			(hide yes)
			(effects
				(font
					(size 1.016 1.016)
					(thickness 0.1524)
				)
			)
		)
		(duplicate_pad_numbers_are_jumpers no)
		(fp_line
			(start 0.508 -0.9398)
			(end -0.508 -0.9398)
			(stroke
				(width 0.1524)
				(type default)
			)
			(layer "F.SilkS")
		)
		(fp_line
			(start -0.508 -0.9398)
			(end -0.508 0.9398)
			(stroke
				(width 0.1524)
				(type default)
			)
			(layer "F.SilkS")
		)
		(fp_rect
			(start -0.508 0.9398)
			(end 0.508 -0.9398)
			(stroke
				(width 0)
				(type default)
			)
			(fill no)
			(layer "F.CrtYd")
		)
		(fp_rect
			(start -0.508 0.9398)
			(end 0.508 -0.9398)
			(stroke
				(width 0)
				(type default)
			)
			(fill no)
			(layer "F.Fab")
		)
		(pad "1" smd custom
			(at 0 -0.4445 180)
			(size 0.1397 0.1397)
			(layers "F.Cu" "F.Mask" "F.Paste")
			(net "P5VA_VFB")
			(options
				(clearance outline)
				(anchor circle)
			)
			(primitives
				(gr_poly
					(pts
						(arc
							(start -0.1778 -0.2794)
							(mid -0.249642 -0.249642)
							(end -0.2794 -0.1778)
						)
						(arc
							(start -0.2794 0.1778)
							(mid -0.249642 0.249642)
							(end -0.1778 0.2794)
						)
						(arc
							(start 0.1778 0.2794)
							(mid 0.249642 0.249642)
							(end 0.2794 0.1778)
						)
						(arc
							(start 0.2794 -0.1778)
							(mid 0.249642 -0.249642)
							(end 0.1778 -0.2794)
						)
					)
					(width 0)
					(fill yes)
				)
			)
		)
		(pad "2" smd custom
			(at 0 0.4445 180)
			(size 0.1397 0.1397)
			(layers "F.Cu" "F.Mask" "F.Paste")
			(net "P5VA_VFB_NET")
			(options
				(clearance outline)
				(anchor circle)
			)
			(primitives
				(gr_poly
					(pts
						(arc
							(start -0.1778 -0.2794)
							(mid -0.249642 -0.249642)
							(end -0.2794 -0.1778)
						)
						(arc
							(start -0.2794 0.1778)
							(mid -0.249642 0.249642)
							(end -0.1778 0.2794)
						)
						(arc
							(start 0.1778 0.2794)
							(mid 0.249642 0.249642)
							(end 0.2794 0.1778)
						)
						(arc
							(start 0.2794 -0.1778)
							(mid 0.249642 -0.249642)
							(end 0.1778 -0.2794)
						)
					)
					(width 0)
					(fill yes)
				)
			)
		)
	)
	(footprint ""
		(layer "F.Cu")
		(at 8.381746 -155.3337 -90)
		(property "Reference" "R356"
			(at 0 0 270)
			(layer "F.SilkS")
			(hide yes)
			(effects
				(font
					(size 1.27 1.27)
				)
			)
		)
		(property "Value" "10KR2F-2-GP"
			(at 0.064008 -3.993896 270)
			(unlocked yes)
			(layer "F.Fab")
			(hide yes)
			(effects
				(font
					(size 1.016 1.016)
					(thickness 0.1524)
				)
			)
		)
		(property "Device Type" "R402H16"
			(at 0.064008 -5.517896 270)
			(unlocked yes)
			(layer "F.Fab")
			(hide yes)
			(effects
				(font
					(size 1.016 1.016)
					(thickness 0.1524)
				)
			)
		)
		(duplicate_pad_numbers_are_jumpers no)
		(fp_line
			(start -0.508 -0.9398)
			(end -0.508 0.9398)
			(stroke
				(width 0.1524)
				(type default)
			)
			(layer "F.SilkS")
		)
		(fp_line
			(start 0.508 -0.9398)
			(end -0.508 -0.9398)
			(stroke
				(width 0.1524)
				(type default)
			)
			(layer "F.SilkS")
		)
		(fp_rect
			(start -0.508 0.9398)
			(end 0.508 -0.9398)
			(stroke
				(width 0)
				(type default)
			)
			(fill no)
			(layer "F.CrtYd")
		)
		(fp_rect
			(start -0.508 0.9398)
			(end 0.508 -0.9398)
			(stroke
				(width 0)
				(type default)
			)
			(fill no)
			(layer "F.Fab")
		)
		(pad "1" smd custom
			(at 0 -0.4445 270)
			(size 0.1397 0.1397)
			(layers "F.Cu" "F.Mask" "F.Paste")
			(net "P3V3")
			(options
				(clearance outline)
				(anchor circle)
			)
			(primitives
				(gr_poly
					(pts
						(arc
							(start -0.1778 -0.2794)
							(mid -0.249642 -0.249642)
							(end -0.2794 -0.1778)
						)
						(arc
							(start -0.2794 0.1778)
							(mid -0.249642 0.249642)
							(end -0.1778 0.2794)
						)
						(arc
							(start 0.1778 0.2794)
							(mid 0.249642 0.249642)
							(end 0.2794 0.1778)
						)
						(arc
							(start 0.2794 -0.1778)
							(mid 0.249642 -0.249642)
							(end 0.1778 -0.2794)
						)
					)
					(width 0)
					(fill yes)
				)
			)
		)
		(pad "2" smd custom
			(at 0 0.4445 270)
			(size 0.1397 0.1397)
			(layers "F.Cu" "F.Mask" "F.Paste")
			(net "TEMP_SENSOR_B_ADDR0&ID")
			(options
				(clearance outline)
				(anchor circle)
			)
			(primitives
				(gr_poly
					(pts
						(arc
							(start -0.1778 -0.2794)
							(mid -0.249642 -0.249642)
							(end -0.2794 -0.1778)
						)
						(arc
							(start -0.2794 0.1778)
							(mid -0.249642 0.249642)
							(end -0.1778 0.2794)
						)
						(arc
							(start 0.1778 0.2794)
							(mid 0.249642 0.249642)
							(end 0.2794 0.1778)
						)
						(arc
							(start 0.2794 -0.1778)
							(mid 0.249642 -0.249642)
							(end 0.1778 -0.2794)
						)
					)
					(width 0)
					(fill yes)
				)
			)
		)
	)
	(footprint ""
		(layer "F.Cu")
		(at 33.043368 -476.060516 -90)
		(property "Reference" "C185"
			(at 0 0 270)
			(layer "F.SilkS")
			(hide yes)
			(effects
				(font
					(size 1.27 1.27)
				)
			)
		)
		(property "Value" "SCD01U50V2KX-1GP"
			(at 1.1811 -2.7051 270)
			(unlocked yes)
			(layer "F.Fab")
			(hide yes)
			(effects
				(font
					(size 1.016 1.016)
					(thickness 0.1524)
				)
			)
		)
		(property "Device Type" "C402H22"
			(at 1.1811 -4.2291 270)
			(unlocked yes)
			(layer "F.Fab")
			(hide yes)
			(effects
				(font
					(size 1.016 1.016)
					(thickness 0.1524)
				)
			)
		)
		(duplicate_pad_numbers_are_jumpers no)
		(fp_rect
			(start -0.4318 0.9525)
			(end 0.4318 -0.9525)
			(stroke
				(width 0)
				(type default)
			)
			(fill no)
			(layer "F.CrtYd")
		)
		(fp_rect
			(start -0.4318 0.9525)
			(end 0.4318 -0.9525)
			(stroke
				(width 0)
				(type default)
			)
			(fill no)
			(layer "F.Fab")
		)
		(pad "1" smd custom
			(at 0 -0.4445 270)
			(size 0.1524 0.1524)
			(layers "F.Cu" "F.Mask" "F.Paste")
			(net "SAS2X28_DRIVE_RX_P_B5")
			(options
				(clearance outline)
				(anchor circle)
			)
			(primitives
				(gr_poly
					(pts
						(arc
							(start 0.3048 -0.2032)
							(mid 0.275042 -0.275042)
							(end 0.2032 -0.3048)
						)
						(arc
							(start -0.2032 -0.3048)
							(mid -0.275042 -0.275042)
							(end -0.3048 -0.2032)
						)
						(arc
							(start -0.3048 0.2032)
							(mid -0.275042 0.275042)
							(end -0.2032 0.3048)
						)
						(arc
							(start 0.2032 0.3048)
							(mid 0.275042 0.275042)
							(end 0.3048 0.2032)
						)
					)
					(width 0)
					(fill yes)
				)
			)
		)
		(pad "2" smd custom
			(at 0 0.4445 270)
			(size 0.1524 0.1524)
			(layers "F.Cu" "F.Mask" "F.Paste")
			(net "SAS2X28_B_HDD5_RX_+")
			(options
				(clearance outline)
				(anchor circle)
			)
			(primitives
				(gr_poly
					(pts
						(arc
							(start 0.3048 -0.2032)
							(mid 0.275042 -0.275042)
							(end 0.2032 -0.3048)
						)
						(arc
							(start -0.2032 -0.3048)
							(mid -0.275042 -0.275042)
							(end -0.3048 -0.2032)
						)
						(arc
							(start -0.3048 0.2032)
							(mid -0.275042 0.275042)
							(end -0.2032 0.3048)
						)
						(arc
							(start 0.2032 0.3048)
							(mid 0.275042 0.275042)
							(end 0.3048 0.2032)
						)
					)
					(width 0)
					(fill yes)
				)
			)
		)
	)
	(footprint ""
		(layer "F.Cu")
		(at 206.882746 -459.4987 -90)
		(property "Reference" "TP3"
			(at 0 0 270)
			(layer "F.SilkS")
			(hide yes)
			(effects
				(font
					(size 1.27 1.27)
				)
			)
		)
		(property "Value" "TPAD32-GP"
			(at 0 -3.166364 270)
			(unlocked yes)
			(layer "F.Fab")
			(hide yes)
			(effects
				(font
					(size 1.016 1.016)
					(thickness 0.1524)
				)
			)
		)
		(property "Device Type" "TPAD32"
			(at 0 -4.690618 270)
			(unlocked yes)
			(layer "F.Fab")
			(hide yes)
			(effects
				(font
					(size 1.016 1.016)
					(thickness 0.1524)
				)
			)
		)
		(duplicate_pad_numbers_are_jumpers no)
		(fp_poly
			(pts
				(arc
					(start 0 -0.4064)
					(mid 0 0.4064)
					(end 0 -0.4064)
				)
			)
			(stroke
				(width 0)
				(type default)
			)
			(fill no)
			(layer "F.CrtYd")
		)
		(fp_poly
			(pts
				(arc
					(start 0 -0.7112)
					(mid 0 0.7112)
					(end 0 -0.7112)
				)
			)
			(stroke
				(width 0)
				(type default)
			)
			(fill no)
			(layer "F.Fab")
		)
		(pad "1" smd circle
			(at 0 0 270)
			(size 0.8128 0.8128)
			(layers "F.Cu" "F.Mask" "F.Paste")
			(net "I2C_B_TMP3_ALERT")
		)
	)
	(footprint ""
		(layer "F.Cu")
		(at 58.6486 -172.72 180)
		(property "Reference" "Q63"
			(at 0 0 180)
			(layer "F.SilkS")
			(hide yes)
			(effects
				(font
					(size 1.27 1.27)
				)
			)
		)
		(property "Value" "2N7002-11-GP"
			(at 0.127 -8.9662 180)
			(unlocked yes)
			(layer "F.Fab")
			(hide yes)
			(effects
				(font
					(size 1.016 1.016)
					(thickness 0.1524)
				)
			)
		)
		(property "Device Type" "SOT23DGS2D4H44"
			(at 0.127 -10.4902 180)
			(unlocked yes)
			(layer "F.Fab")
			(hide yes)
			(effects
				(font
					(size 1.016 1.016)
					(thickness 0.1524)
				)
			)
		)
		(duplicate_pad_numbers_are_jumpers no)
		(fp_line
			(start 1.651 1.778)
			(end 1.651 -1.778)
			(stroke
				(width 0.1524)
				(type default)
			)
			(layer "F.SilkS")
		)
		(fp_line
			(start 1.651 -1.778)
			(end -1.651 -1.778)
			(stroke
				(width 0.1524)
				(type default)
			)
			(layer "F.SilkS")
		)
		(fp_line
			(start -1.651 1.778)
			(end 1.651 1.778)
			(stroke
				(width 0.1524)
				(type default)
			)
			(layer "F.SilkS")
		)
		(fp_line
			(start -1.651 -1.778)
			(end -1.651 1.778)
			(stroke
				(width 0.1524)
				(type default)
			)
			(layer "F.SilkS")
		)
		(fp_poly
			(pts
				(xy -1.778 1.8796) (xy -1.778 -1.8796) (xy 1.778 -1.8796) (xy 1.778 1.8796)
			)
			(stroke
				(width 0)
				(type default)
			)
			(fill no)
			(layer "F.CrtYd")
		)
		(fp_poly
			(pts
				(xy -1.778 1.8796) (xy -1.778 -1.8796) (xy 1.778 -1.8796) (xy 1.778 1.8796)
			)
			(stroke
				(width 0)
				(type default)
			)
			(fill no)
			(layer "F.Fab")
		)
		(pad "D" smd custom
			(at 0 -0.9525 180)
			(size 0.1905 0.1905)
			(layers "F.Cu" "F.Mask" "F.Paste")
			(net "HDD8_LED_G")
			(options
				(clearance outline)
				(anchor circle)
			)
			(primitives
				(gr_poly
					(pts
						(arc
							(start -0.1778 0.5715)
							(mid -0.321484 0.511984)
							(end -0.381 0.3683)
						)
						(arc
							(start -0.381 -0.3683)
							(mid -0.321484 -0.511984)
							(end -0.1778 -0.5715)
						)
						(arc
							(start 0.1778 -0.5715)
							(mid 0.321484 -0.511984)
							(end 0.381 -0.3683)
						)
						(arc
							(start 0.381 0.3683)
							(mid 0.321484 0.511984)
							(end 0.1778 0.5715)
						)
					)
					(width 0)
					(fill yes)
				)
			)
		)
		(pad "G" smd custom
			(at -0.98425 0.9525 180)
			(size 0.1905 0.1905)
			(layers "F.Cu" "F.Mask" "F.Paste")
			(net "HDD8_LED_B")
			(options
				(clearance outline)
				(anchor circle)
			)
			(primitives
				(gr_poly
					(pts
						(arc
							(start -0.1778 0.5715)
							(mid -0.321484 0.511984)
							(end -0.381 0.3683)
						)
						(arc
							(start -0.381 -0.3683)
							(mid -0.321484 -0.511984)
							(end -0.1778 -0.5715)
						)
						(arc
							(start 0.1778 -0.5715)
							(mid 0.321484 -0.511984)
							(end 0.381 -0.3683)
						)
						(arc
							(start 0.381 0.3683)
							(mid 0.321484 0.511984)
							(end 0.1778 0.5715)
						)
					)
					(width 0)
					(fill yes)
				)
			)
		)
		(pad "S" smd custom
			(at 0.98425 0.9525 180)
			(size 0.1905 0.1905)
			(layers "F.Cu" "F.Mask" "F.Paste")
			(net "GND")
			(options
				(clearance outline)
				(anchor circle)
			)
			(primitives
				(gr_poly
					(pts
						(arc
							(start -0.1778 0.5715)
							(mid -0.321484 0.511984)
							(end -0.381 0.3683)
						)
						(arc
							(start -0.381 -0.3683)
							(mid -0.321484 -0.511984)
							(end -0.1778 -0.5715)
						)
						(arc
							(start 0.1778 -0.5715)
							(mid 0.321484 -0.511984)
							(end 0.381 -0.3683)
						)
						(arc
							(start 0.381 0.3683)
							(mid 0.321484 0.511984)
							(end 0.1778 0.5715)
						)
					)
					(width 0)
					(fill yes)
				)
			)
		)
	)
	(footprint ""
		(layer "F.Cu")
		(at 224.747582 -246.860568 90)
		(property "Reference" "R131"
			(at 0 0 90)
			(layer "F.SilkS")
			(hide yes)
			(effects
				(font
					(size 1.27 1.27)
				)
			)
		)
		(property "Value" "330R2F-GP"
			(at 0.064008 -3.993896 90)
			(unlocked yes)
			(layer "F.Fab")
			(hide yes)
			(effects
				(font
					(size 1.016 1.016)
					(thickness 0.1524)
				)
			)
		)
		(property "Device Type" "R402H16"
			(at 0.064008 -5.517896 90)
			(unlocked yes)
			(layer "F.Fab")
			(hide yes)
			(effects
				(font
					(size 1.016 1.016)
					(thickness 0.1524)
				)
			)
		)
		(duplicate_pad_numbers_are_jumpers no)
		(fp_line
			(start 0.508 -0.9398)
			(end -0.508 -0.9398)
			(stroke
				(width 0.1524)
				(type default)
			)
			(layer "F.SilkS")
		)
		(fp_line
			(start -0.508 -0.9398)
			(end -0.508 0.9398)
			(stroke
				(width 0.1524)
				(type default)
			)
			(layer "F.SilkS")
		)
		(fp_rect
			(start -0.508 0.9398)
			(end 0.508 -0.9398)
			(stroke
				(width 0)
				(type default)
			)
			(fill no)
			(layer "F.CrtYd")
		)
		(fp_rect
			(start -0.508 0.9398)
			(end 0.508 -0.9398)
			(stroke
				(width 0)
				(type default)
			)
			(fill no)
			(layer "F.Fab")
		)
		(pad "1" smd custom
			(at 0 -0.4445 90)
			(size 0.1397 0.1397)
			(layers "F.Cu" "F.Mask" "F.Paste")
			(net "P3V3_HDD2_LED")
			(options
				(clearance outline)
				(anchor circle)
			)
			(primitives
				(gr_poly
					(pts
						(arc
							(start -0.1778 -0.2794)
							(mid -0.249642 -0.249642)
							(end -0.2794 -0.1778)
						)
						(arc
							(start -0.2794 0.1778)
							(mid -0.249642 0.249642)
							(end -0.1778 0.2794)
						)
						(arc
							(start 0.1778 0.2794)
							(mid 0.249642 0.249642)
							(end 0.2794 0.1778)
						)
						(arc
							(start 0.2794 -0.1778)
							(mid 0.249642 -0.249642)
							(end 0.1778 -0.2794)
						)
					)
					(width 0)
					(fill yes)
				)
			)
		)
		(pad "2" smd custom
			(at 0 0.4445 90)
			(size 0.1397 0.1397)
			(layers "F.Cu" "F.Mask" "F.Paste")
			(net "FLT_HDD2")
			(options
				(clearance outline)
				(anchor circle)
			)
			(primitives
				(gr_poly
					(pts
						(arc
							(start -0.1778 -0.2794)
							(mid -0.249642 -0.249642)
							(end -0.2794 -0.1778)
						)
						(arc
							(start -0.2794 0.1778)
							(mid -0.249642 0.249642)
							(end -0.1778 0.2794)
						)
						(arc
							(start 0.1778 0.2794)
							(mid 0.249642 0.249642)
							(end 0.2794 0.1778)
						)
						(arc
							(start 0.2794 -0.1778)
							(mid 0.249642 -0.249642)
							(end 0.1778 -0.2794)
						)
					)
					(width 0)
					(fill yes)
				)
			)
		)
	)
	(footprint ""
		(layer "F.Cu")
		(at 78.994 -192.151)
		(property "Reference" "C372"
			(at 0 0 0)
			(layer "F.SilkS")
			(hide yes)
			(effects
				(font
					(size 1.27 1.27)
				)
			)
		)
		(property "Value" "SCD033U25V2KX-GP"
			(at 1.1811 -2.7051 0)
			(unlocked yes)
			(layer "F.Fab")
			(hide yes)
			(effects
				(font
					(size 1.016 1.016)
					(thickness 0.1524)
				)
			)
		)
		(property "Device Type" "C402H22"
			(at 1.1811 -4.2291 0)
			(unlocked yes)
			(layer "F.Fab")
			(hide yes)
			(effects
				(font
					(size 1.016 1.016)
					(thickness 0.1524)
				)
			)
		)
		(duplicate_pad_numbers_are_jumpers no)
		(fp_rect
			(start -0.4318 0.9525)
			(end 0.4318 -0.9525)
			(stroke
				(width 0)
				(type default)
			)
			(fill no)
			(layer "F.CrtYd")
		)
		(fp_rect
			(start -0.4318 0.9525)
			(end 0.4318 -0.9525)
			(stroke
				(width 0)
				(type default)
			)
			(fill no)
			(layer "F.Fab")
		)
		(pad "1" smd custom
			(at 0 -0.4445)
			(size 0.1524 0.1524)
			(layers "F.Cu" "F.Mask" "F.Paste")
			(net "SW_HDD8_P")
			(options
				(clearance outline)
				(anchor circle)
			)
			(primitives
				(gr_poly
					(pts
						(arc
							(start 0.3048 -0.2032)
							(mid 0.275042 -0.275042)
							(end 0.2032 -0.3048)
						)
						(arc
							(start -0.2032 -0.3048)
							(mid -0.275042 -0.275042)
							(end -0.3048 -0.2032)
						)
						(arc
							(start -0.3048 0.2032)
							(mid -0.275042 0.275042)
							(end -0.2032 0.3048)
						)
						(arc
							(start 0.2032 0.3048)
							(mid 0.275042 0.275042)
							(end 0.3048 0.2032)
						)
					)
					(width 0)
					(fill yes)
				)
			)
		)
		(pad "2" smd custom
			(at 0 0.4445)
			(size 0.1524 0.1524)
			(layers "F.Cu" "F.Mask" "F.Paste")
			(net "GND")
			(options
				(clearance outline)
				(anchor circle)
			)
			(primitives
				(gr_poly
					(pts
						(arc
							(start 0.3048 -0.2032)
							(mid 0.275042 -0.275042)
							(end 0.2032 -0.3048)
						)
						(arc
							(start -0.2032 -0.3048)
							(mid -0.275042 -0.275042)
							(end -0.3048 -0.2032)
						)
						(arc
							(start -0.3048 0.2032)
							(mid -0.275042 0.275042)
							(end -0.2032 0.3048)
						)
						(arc
							(start 0.2032 0.3048)
							(mid 0.275042 0.275042)
							(end 0.3048 0.2032)
						)
					)
					(width 0)
					(fill yes)
				)
			)
		)
	)
	(footprint ""
		(layer "F.Cu")
		(at 62.610492 -82.451956)
		(property "Reference" "C255"
			(at 0 0 0)
			(layer "F.SilkS")
			(hide yes)
			(effects
				(font
					(size 1.27 1.27)
				)
			)
		)
		(property "Value" "SC10U25V6KX-1GP"
			(at -0.0762 -5.1308 0)
			(unlocked yes)
			(layer "F.Fab")
			(hide yes)
			(effects
				(font
					(size 1.016 1.016)
					(thickness 0.1524)
				)
			)
		)
		(property "Device Type" "C1206H71"
			(at -0.127 -6.6548 0)
			(unlocked yes)
			(layer "F.Fab")
			(hide yes)
			(effects
				(font
					(size 1.016 1.016)
					(thickness 0.1524)
				)
			)
		)
		(duplicate_pad_numbers_are_jumpers no)
		(fp_line
			(start -1.016 -2.2352)
			(end 1.016 -2.2352)
			(stroke
				(width 0.1524)
				(type default)
			)
			(layer "F.SilkS")
		)
		(fp_line
			(start -1.016 -0.8382)
			(end -1.016 -2.2352)
			(stroke
				(width 0.1524)
				(type default)
			)
			(layer "F.SilkS")
		)
		(fp_line
			(start -1.016 2.2352)
			(end -1.016 0.8382)
			(stroke
				(width 0.1524)
				(type default)
			)
			(layer "F.SilkS")
		)
		(fp_line
			(start 1.016 -2.2352)
			(end 1.016 -0.8382)
			(stroke
				(width 0.1524)
				(type default)
			)
			(layer "F.SilkS")
		)
		(fp_line
			(start 1.016 0.8382)
			(end 1.016 2.2352)
			(stroke
				(width 0.1524)
				(type default)
			)
			(layer "F.SilkS")
		)
		(fp_line
			(start 1.016 2.2352)
			(end -1.016 2.2352)
			(stroke
				(width 0.1524)
				(type default)
			)
			(layer "F.SilkS")
		)
		(fp_rect
			(start -1.0922 2.3114)
			(end 1.0922 -2.3114)
			(stroke
				(width 0)
				(type default)
			)
			(fill no)
			(layer "F.CrtYd")
		)
		(fp_poly
			(pts
				(xy 1.0922 -2.3114) (xy 1.0922 2.3114) (xy -1.0922 2.3114) (xy -1.0922 -2.3114)
			)
			(stroke
				(width 0)
				(type default)
			)
			(fill no)
			(layer "F.Fab")
		)
		(pad "1" smd rect
			(at 0 -1.397)
			(size 1.651 1.27)
			(layers "F.Cu" "F.Mask" "F.Paste")
			(net "P12V_HDD9")
		)
		(pad "2" smd rect
			(at 0 1.397)
			(size 1.651 1.27)
			(layers "F.Cu" "F.Mask" "F.Paste")
			(net "GND")
		)
	)
)
